(kicad_pcb
	(version 20241229)
	(generator "pcbnew")
	(generator_version "9.0")
	(general
		(thickness 1.599998)
		(legacy_teardrops no)
	)
	(paper "A4")
	(title_block
		(title "Artix - Datacenter Secure Control Module (DC-SCM)")
		(date "2024-11-06")
		(rev "1.1.3")
		(comment 9 "footprints 240-244 of 544")
	)
	(layers
		(0 "F.Cu" signal)
		(4 "In1.Cu" signal)
		(6 "In2.Cu" signal)
		(8 "In3.Cu" signal)
		(10 "In4.Cu" signal)
		(12 "In5.Cu" signal)
		(14 "In6.Cu" signal)
		(2 "B.Cu" signal)
		(9 "F.Adhes" user "F.Adhesive")
		(11 "B.Adhes" user "B.Adhesive")
		(13 "F.Paste" user)
		(15 "B.Paste" user)
		(5 "F.SilkS" user "F.Silkscreen")
		(7 "B.SilkS" user "B.Silkscreen")
		(1 "F.Mask" user)
		(3 "B.Mask" user)
		(17 "Dwgs.User" user "User.Drawings")
		(19 "Cmts.User" user "User.Comments")
		(21 "Eco1.User" user "User.Eco1")
		(23 "Eco2.User" user "User.Eco2")
		(25 "Edge.Cuts" user)
		(27 "Margin" user)
		(31 "F.CrtYd" user "F.Courtyard")
		(29 "B.CrtYd" user "B.Courtyard")
		(35 "F.Fab" user)
		(33 "B.Fab" user)
	)
	(footprint "antmicro-footprints:C_0402_1005Metric"
		(layer "F.Cu")
		(at 132.45 88.7125 -90)
		(descr "Capacitor SMD 0402")
		(tags "capacitor SMD 0402")
		(property "Reference" "C154"
			(at -3.7125 -0.35 90)
			(layer "F.SilkS")
			(effects
				(font
					(size 0.7 0.7)
					(thickness 0.15)
				)
				(justify right bottom)
			)
		)
		(property "Value" "C_4u7_0402"
			(at 0 1.4 90)
			(layer "F.Fab")
			(effects
				(font
					(size 0.7 0.7)
					(thickness 0.15)
				)
				(justify right bottom)
			)
		)
		(property "Datasheet" "https://www.murata.com/products/productdetail?partno=GRM155R61A475MEAA%23"
			(at 0 0 270)
			(layer "F.Fab")
			(hide yes)
			(effects
				(font
					(size 1.27 1.27)
					(thickness 0.15)
				)
			)
		)
		(property "Description" "SMD Multilayer Ceramic Capacitor, 4.7 µF, 10 V, 0402 [1005 Metric], ± 20%, X5R, GRM Series"
			(at 0 0 270)
			(layer "F.Fab")
			(hide yes)
			(effects
				(font
					(size 1.27 1.27)
					(thickness 0.15)
				)
			)
		)
		(property "Author" "Antmicro"
			(at 43.7375 221.1625 0)
			(layer "F.Fab")
			(hide yes)
			(effects
				(font
					(size 1 1)
					(thickness 0.15)
				)
			)
		)
		(property "Dielectric" ""
			(at 43.7375 221.1625 0)
			(layer "F.Fab")
			(hide yes)
			(effects
				(font
					(size 1 1)
					(thickness 0.15)
				)
			)
		)
		(property "License" "Apache-2.0"
			(at 43.7375 221.1625 0)
			(layer "F.Fab")
			(hide yes)
			(effects
				(font
					(size 1 1)
					(thickness 0.15)
				)
			)
		)
		(property "MPN" "GRM155R61A475MEAAD"
			(at 43.7375 221.1625 0)
			(layer "F.Fab")
			(hide yes)
			(effects
				(font
					(size 1 1)
					(thickness 0.15)
				)
			)
		)
		(property "Manufacturer" "Murata"
			(at 43.7375 221.1625 0)
			(layer "F.Fab")
			(hide yes)
			(effects
				(font
					(size 1 1)
					(thickness 0.15)
				)
			)
		)
		(property "Val" "4u7"
			(at 43.7375 221.1625 0)
			(layer "F.Fab")
			(hide yes)
			(effects
				(font
					(size 1 1)
					(thickness 0.15)
				)
			)
		)
		(property "Voltage" ""
			(at 43.7375 221.1625 0)
			(layer "F.Fab")
			(hide yes)
			(effects
				(font
					(size 1 1)
					(thickness 0.15)
				)
			)
		)
		(sheetname "/Interfaces/")
		(sheetfile "interfaces.kicad_sch")
		(attr smd)
		(fp_rect
			(start -0.925 -0.47)
			(end 0.925 0.47)
			(stroke
				(width 0.05)
				(type default)
			)
			(fill no)
			(layer "F.CrtYd")
		)
		(fp_line
			(start -0.494 0.248)
			(end -0.494 -0.25)
			(stroke
				(width 0.15)
				(type solid)
			)
			(layer "F.Fab")
		)
		(fp_line
			(start 0.504 0.248)
			(end -0.494 0.248)
			(stroke
				(width 0.15)
				(type solid)
			)
			(layer "F.Fab")
		)
		(fp_line
			(start -0.494 -0.25)
			(end 0.504 -0.25)
			(stroke
				(width 0.15)
				(type solid)
			)
			(layer "F.Fab")
		)
		(fp_line
			(start 0.504 -0.25)
			(end 0.504 0.248)
			(stroke
				(width 0.15)
				(type solid)
			)
			(layer "F.Fab")
		)
		(pad "1" smd roundrect
			(at -0.48 0 270)
			(size 0.59 0.64)
			(layers "F.Cu" "F.Mask" "F.Paste")
			(roundrect_rratio 0.25)
			(net 1 "GND")
			(pintype "passive")
		)
		(pad "2" smd roundrect
			(at 0.48 0 270)
			(size 0.59 0.64)
			(layers "F.Cu" "F.Mask" "F.Paste")
			(roundrect_rratio 0.25)
			(net 116 "/Interfaces/FT_VPLL")
			(pintype "passive")
		)
	)
	(footprint "antmicro-footprints:C_0402_1005Metric"
		(layer "F.Cu")
		(at 139.5 83.5 180)
		(descr "Capacitor SMD 0402")
		(tags "capacitor SMD 0402")
		(property "Reference" "C166"
			(at -1.4 0.6 0)
			(layer "F.SilkS")
			(effects
				(font
					(size 0.7 0.7)
					(thickness 0.15)
				)
				(justify right bottom)
			)
		)
		(property "Value" "C_18p_0402"
			(at 0 1.4 0)
			(layer "F.Fab")
			(effects
				(font
					(size 0.7 0.7)
					(thickness 0.15)
				)
				(justify right bottom)
			)
		)
		(property "Datasheet" "https://product.samsungsem.com/mlcc/CL05C180JB51PN.do"
			(at 0 0 180)
			(layer "F.Fab")
			(hide yes)
			(effects
				(font
					(size 1.27 1.27)
					(thickness 0.15)
				)
			)
		)
		(property "Description" "SMD Multilayer Ceramic Capacitor, 18 pF, 50 V, 0402 [1005 Metric], ± 5%, C0G / NP0, MC"
			(at 0 0 180)
			(layer "F.Fab")
			(hide yes)
			(effects
				(font
					(size 1.27 1.27)
					(thickness 0.15)
				)
			)
		)
		(property "Author" "Antmicro"
			(at 279 167 0)
			(layer "F.Fab")
			(hide yes)
			(effects
				(font
					(size 1 1)
					(thickness 0.15)
				)
			)
		)
		(property "Dielectric" ""
			(at 279 167 0)
			(layer "F.Fab")
			(hide yes)
			(effects
				(font
					(size 1 1)
					(thickness 0.15)
				)
			)
		)
		(property "License" "Apache-2.0"
			(at 279 167 0)
			(layer "F.Fab")
			(hide yes)
			(effects
				(font
					(size 1 1)
					(thickness 0.15)
				)
			)
		)
		(property "MPN" "CL05C180JB51PNC"
			(at 279 167 0)
			(layer "F.Fab")
			(hide yes)
			(effects
				(font
					(size 1 1)
					(thickness 0.15)
				)
			)
		)
		(property "Manufacturer" "Samsung Electro-Mechanics"
			(at 279 167 0)
			(layer "F.Fab")
			(hide yes)
			(effects
				(font
					(size 1 1)
					(thickness 0.15)
				)
			)
		)
		(property "Val" "18p"
			(at 279 167 0)
			(layer "F.Fab")
			(hide yes)
			(effects
				(font
					(size 1 1)
					(thickness 0.15)
				)
			)
		)
		(property "Voltage" ""
			(at 279 167 0)
			(layer "F.Fab")
			(hide yes)
			(effects
				(font
					(size 1 1)
					(thickness 0.15)
				)
			)
		)
		(sheetname "/Interfaces/")
		(sheetfile "interfaces.kicad_sch")
		(attr smd)
		(fp_rect
			(start -0.925 -0.47)
			(end 0.925 0.47)
			(stroke
				(width 0.05)
				(type default)
			)
			(fill no)
			(layer "F.CrtYd")
		)
		(fp_line
			(start 0.504 0.248)
			(end -0.494 0.248)
			(stroke
				(width 0.15)
				(type solid)
			)
			(layer "F.Fab")
		)
		(fp_line
			(start 0.504 -0.25)
			(end 0.504 0.248)
			(stroke
				(width 0.15)
				(type solid)
			)
			(layer "F.Fab")
		)
		(fp_line
			(start -0.494 0.248)
			(end -0.494 -0.25)
			(stroke
				(width 0.15)
				(type solid)
			)
			(layer "F.Fab")
		)
		(fp_line
			(start -0.494 -0.25)
			(end 0.504 -0.25)
			(stroke
				(width 0.15)
				(type solid)
			)
			(layer "F.Fab")
		)
		(pad "1" smd roundrect
			(at -0.48 0 180)
			(size 0.59 0.64)
			(layers "F.Cu" "F.Mask" "F.Paste")
			(roundrect_rratio 0.25)
			(net 1 "GND")
			(pintype "passive")
		)
		(pad "2" smd roundrect
			(at 0.48 0 180)
			(size 0.59 0.64)
			(layers "F.Cu" "F.Mask" "F.Paste")
			(roundrect_rratio 0.25)
			(net 197 "Net-(U19-OSCI)")
			(pintype "passive")
		)
	)
	(footprint "antmicro-footprints:C_0402_1005Metric"
		(layer "F.Cu")
		(at 134.55 86.3125 -90)
		(descr "Capacitor SMD 0402")
		(tags "capacitor SMD 0402")
		(property "Reference" "C168"
			(at 0.8875 -0.45 90)
			(layer "F.SilkS")
			(effects
				(font
					(size 0.7 0.7)
					(thickness 0.15)
				)
				(justify right bottom)
			)
		)
		(property "Value" "C_18p_0402"
			(at 0 1.4 90)
			(layer "F.Fab")
			(effects
				(font
					(size 0.7 0.7)
					(thickness 0.15)
				)
				(justify right bottom)
			)
		)
		(property "Datasheet" "https://product.samsungsem.com/mlcc/CL05C180JB51PN.do"
			(at 0 0 270)
			(layer "F.Fab")
			(hide yes)
			(effects
				(font
					(size 1.27 1.27)
					(thickness 0.15)
				)
			)
		)
		(property "Description" "SMD Multilayer Ceramic Capacitor, 18 pF, 50 V, 0402 [1005 Metric], ± 5%, C0G / NP0, MC"
			(at 0 0 270)
			(layer "F.Fab")
			(hide yes)
			(effects
				(font
					(size 1.27 1.27)
					(thickness 0.15)
				)
			)
		)
		(property "Author" "Antmicro"
			(at 48.2375 220.8625 0)
			(layer "F.Fab")
			(hide yes)
			(effects
				(font
					(size 1 1)
					(thickness 0.15)
				)
			)
		)
		(property "Dielectric" ""
			(at 48.2375 220.8625 0)
			(layer "F.Fab")
			(hide yes)
			(effects
				(font
					(size 1 1)
					(thickness 0.15)
				)
			)
		)
		(property "License" "Apache-2.0"
			(at 48.2375 220.8625 0)
			(layer "F.Fab")
			(hide yes)
			(effects
				(font
					(size 1 1)
					(thickness 0.15)
				)
			)
		)
		(property "MPN" "CL05C180JB51PNC"
			(at 48.2375 220.8625 0)
			(layer "F.Fab")
			(hide yes)
			(effects
				(font
					(size 1 1)
					(thickness 0.15)
				)
			)
		)
		(property "Manufacturer" "Samsung Electro-Mechanics"
			(at 48.2375 220.8625 0)
			(layer "F.Fab")
			(hide yes)
			(effects
				(font
					(size 1 1)
					(thickness 0.15)
				)
			)
		)
		(property "Val" "18p"
			(at 48.2375 220.8625 0)
			(layer "F.Fab")
			(hide yes)
			(effects
				(font
					(size 1 1)
					(thickness 0.15)
				)
			)
		)
		(property "Voltage" ""
			(at 48.2375 220.8625 0)
			(layer "F.Fab")
			(hide yes)
			(effects
				(font
					(size 1 1)
					(thickness 0.15)
				)
			)
		)
		(sheetname "/Interfaces/")
		(sheetfile "interfaces.kicad_sch")
		(attr smd)
		(fp_rect
			(start -0.925 -0.47)
			(end 0.925 0.47)
			(stroke
				(width 0.05)
				(type default)
			)
			(fill no)
			(layer "F.CrtYd")
		)
		(fp_line
			(start -0.494 0.248)
			(end -0.494 -0.25)
			(stroke
				(width 0.15)
				(type solid)
			)
			(layer "F.Fab")
		)
		(fp_line
			(start 0.504 0.248)
			(end -0.494 0.248)
			(stroke
				(width 0.15)
				(type solid)
			)
			(layer "F.Fab")
		)
		(fp_line
			(start -0.494 -0.25)
			(end 0.504 -0.25)
			(stroke
				(width 0.15)
				(type solid)
			)
			(layer "F.Fab")
		)
		(fp_line
			(start 0.504 -0.25)
			(end 0.504 0.248)
			(stroke
				(width 0.15)
				(type solid)
			)
			(layer "F.Fab")
		)
		(pad "1" smd roundrect
			(at -0.48 0 270)
			(size 0.59 0.64)
			(layers "F.Cu" "F.Mask" "F.Paste")
			(roundrect_rratio 0.25)
			(net 1 "GND")
			(pintype "passive")
		)
		(pad "2" smd roundrect
			(at 0.48 0 270)
			(size 0.59 0.64)
			(layers "F.Cu" "F.Mask" "F.Paste")
			(roundrect_rratio 0.25)
			(net 198 "Net-(U19-OSCO)")
			(pintype "passive")
		)
	)
	(footprint "antmicro-footprints:C_0402_1005Metric"
		(layer "F.Cu")
		(at 141.35 98.0125 180)
		(descr "Capacitor SMD 0402")
		(tags "capacitor SMD 0402")
		(property "Reference" "C169"
			(at -3.65 -0.2875 0)
			(layer "F.SilkS")
			(effects
				(font
					(size 0.7 0.7)
					(thickness 0.15)
				)
				(justify right bottom)
			)
		)
		(property "Value" "C_100n_0402"
			(at 0 1.4 0)
			(layer "F.Fab")
			(effects
				(font
					(size 0.7 0.7)
					(thickness 0.15)
				)
				(justify right bottom)
			)
		)
		(property "Datasheet" "https://www.murata.com/products/productdetail?partno=GRM155R61H104KE14%23"
			(at 0 0 180)
			(layer "F.Fab")
			(hide yes)
			(effects
				(font
					(size 1.27 1.27)
					(thickness 0.15)
				)
			)
		)
		(property "Description" "SMD Multilayer Ceramic Capacitor, 0.1 µF, 50 V, 0402 [1005 Metric], ± 10%, X5R, GRM Series"
			(at 0 0 180)
			(layer "F.Fab")
			(hide yes)
			(effects
				(font
					(size 1.27 1.27)
					(thickness 0.15)
				)
			)
		)
		(property "Author" "Antmicro"
			(at 282.7 196.025 0)
			(layer "F.Fab")
			(hide yes)
			(effects
				(font
					(size 1 1)
					(thickness 0.15)
				)
			)
		)
		(property "Dielectric" "X5R"
			(at 282.7 196.025 0)
			(layer "F.Fab")
			(hide yes)
			(effects
				(font
					(size 1 1)
					(thickness 0.15)
				)
			)
		)
		(property "License" "Apache-2.0"
			(at 282.7 196.025 0)
			(layer "F.Fab")
			(hide yes)
			(effects
				(font
					(size 1 1)
					(thickness 0.15)
				)
			)
		)
		(property "MPN" "GRM155R61H104KE14D"
			(at 282.7 196.025 0)
			(layer "F.Fab")
			(hide yes)
			(effects
				(font
					(size 1 1)
					(thickness 0.15)
				)
			)
		)
		(property "Manufacturer" "Murata"
			(at 282.7 196.025 0)
			(layer "F.Fab")
			(hide yes)
			(effects
				(font
					(size 1 1)
					(thickness 0.15)
				)
			)
		)
		(property "Val" "100n"
			(at 282.7 196.025 0)
			(layer "F.Fab")
			(hide yes)
			(effects
				(font
					(size 1 1)
					(thickness 0.15)
				)
			)
		)
		(property "Voltage" "50V"
			(at 282.7 196.025 0)
			(layer "F.Fab")
			(hide yes)
			(effects
				(font
					(size 1 1)
					(thickness 0.15)
				)
			)
		)
		(sheetname "/Interfaces/")
		(sheetfile "interfaces.kicad_sch")
		(attr smd)
		(fp_rect
			(start -0.925 -0.47)
			(end 0.925 0.47)
			(stroke
				(width 0.05)
				(type default)
			)
			(fill no)
			(layer "F.CrtYd")
		)
		(fp_line
			(start 0.504 0.248)
			(end -0.494 0.248)
			(stroke
				(width 0.15)
				(type solid)
			)
			(layer "F.Fab")
		)
		(fp_line
			(start 0.504 -0.25)
			(end 0.504 0.248)
			(stroke
				(width 0.15)
				(type solid)
			)
			(layer "F.Fab")
		)
		(fp_line
			(start -0.494 0.248)
			(end -0.494 -0.25)
			(stroke
				(width 0.15)
				(type solid)
			)
			(layer "F.Fab")
		)
		(fp_line
			(start -0.494 -0.25)
			(end 0.504 -0.25)
			(stroke
				(width 0.15)
				(type solid)
			)
			(layer "F.Fab")
		)
		(pad "1" smd roundrect
			(at -0.48 0 180)
			(size 0.59 0.64)
			(layers "F.Cu" "F.Mask" "F.Paste")
			(roundrect_rratio 0.25)
			(net 1 "GND")
			(pintype "passive")
		)
		(pad "2" smd roundrect
			(at 0.48 0 180)
			(size 0.59 0.64)
			(layers "F.Cu" "F.Mask" "F.Paste")
			(roundrect_rratio 0.25)
			(net 2 "VCC3V3")
			(pintype "passive")
		)
	)
	(footprint "antmicro-footprints:C_0402_1005Metric"
		(layer "F.Cu")
		(at 141.35 95.5125 180)
		(descr "Capacitor SMD 0402")
		(tags "capacitor SMD 0402")
		(property "Reference" "C170"
			(at -3.65 -0.2875 0)
			(layer "F.SilkS")
			(effects
				(font
					(size 0.7 0.7)
					(thickness 0.15)
				)
				(justify right bottom)
			)
		)
		(property "Value" "C_100n_0402"
			(at 0 1.4 0)
			(layer "F.Fab")
			(effects
				(font
					(size 0.7 0.7)
					(thickness 0.15)
				)
				(justify right bottom)
			)
		)
		(property "Datasheet" "https://www.murata.com/products/productdetail?partno=GRM155R61H104KE14%23"
			(at 0 0 180)
			(layer "F.Fab")
			(hide yes)
			(effects
				(font
					(size 1.27 1.27)
					(thickness 0.15)
				)
			)
		)
		(property "Description" "SMD Multilayer Ceramic Capacitor, 0.1 µF, 50 V, 0402 [1005 Metric], ± 10%, X5R, GRM Series"
			(at 0 0 180)
			(layer "F.Fab")
			(hide yes)
			(effects
				(font
					(size 1.27 1.27)
					(thickness 0.15)
				)
			)
		)
		(property "Author" "Antmicro"
			(at 282.7 191.025 0)
			(layer "F.Fab")
			(hide yes)
			(effects
				(font
					(size 1 1)
					(thickness 0.15)
				)
			)
		)
		(property "Dielectric" "X5R"
			(at 282.7 191.025 0)
			(layer "F.Fab")
			(hide yes)
			(effects
				(font
					(size 1 1)
					(thickness 0.15)
				)
			)
		)
		(property "License" "Apache-2.0"
			(at 282.7 191.025 0)
			(layer "F.Fab")
			(hide yes)
			(effects
				(font
					(size 1 1)
					(thickness 0.15)
				)
			)
		)
		(property "MPN" "GRM155R61H104KE14D"
			(at 282.7 191.025 0)
			(layer "F.Fab")
			(hide yes)
			(effects
				(font
					(size 1 1)
					(thickness 0.15)
				)
			)
		)
		(property "Manufacturer" "Murata"
			(at 282.7 191.025 0)
			(layer "F.Fab")
			(hide yes)
			(effects
				(font
					(size 1 1)
					(thickness 0.15)
				)
			)
		)
		(property "Val" "100n"
			(at 282.7 191.025 0)
			(layer "F.Fab")
			(hide yes)
			(effects
				(font
					(size 1 1)
					(thickness 0.15)
				)
			)
		)
		(property "Voltage" "50V"
			(at 282.7 191.025 0)
			(layer "F.Fab")
			(hide yes)
			(effects
				(font
					(size 1 1)
					(thickness 0.15)
				)
			)
		)
		(sheetname "/Interfaces/")
		(sheetfile "interfaces.kicad_sch")
		(attr smd)
		(fp_rect
			(start -0.925 -0.47)
			(end 0.925 0.47)
			(stroke
				(width 0.05)
				(type default)
			)
			(fill no)
			(layer "F.CrtYd")
		)
		(fp_line
			(start 0.504 0.248)
			(end -0.494 0.248)
			(stroke
				(width 0.15)
				(type solid)
			)
			(layer "F.Fab")
		)
		(fp_line
			(start 0.504 -0.25)
			(end 0.504 0.248)
			(stroke
				(width 0.15)
				(type solid)
			)
			(layer "F.Fab")
		)
		(fp_line
			(start -0.494 0.248)
			(end -0.494 -0.25)
			(stroke
				(width 0.15)
				(type solid)
			)
			(layer "F.Fab")
		)
		(fp_line
			(start -0.494 -0.25)
			(end 0.504 -0.25)
			(stroke
				(width 0.15)
				(type solid)
			)
			(layer "F.Fab")
		)
		(pad "1" smd roundrect
			(at -0.48 0 180)
			(size 0.59 0.64)
			(layers "F.Cu" "F.Mask" "F.Paste")
			(roundrect_rratio 0.25)
			(net 1 "GND")
			(pintype "passive")
		)
		(pad "2" smd roundrect
			(at 0.48 0 180)
			(size 0.59 0.64)
			(layers "F.Cu" "F.Mask" "F.Paste")
			(roundrect_rratio 0.25)
			(net 2 "VCC3V3")
			(pintype "passive")
		)
	)
)
